# T6G (Grand Teton) — schematic netlist excerpt (pin names and nets, part order shuffled) for the footprints in the layout excerpt that follows; sources: Cadence DE-HDL packaged netlist, KiCad conversion of 04192023_DAF0TMB3IC0_F0TG_MB_C_brd_V02_OCP.brd

R4091  Q_RES  1K 1% CHIP  pkg 0402LF  page 237 : A = P3V3_AUX ; B = P12V_SCM_ADC_ALERT_R
PC202_2  Q_CAP  0.1UF 25V 10% X7R  pkg 0402  page 208 : A = PVDD11_S3_P0_VCCS ; B = GND

(kicad_pcb
	(version 20260206)
	(generator "pcbnew")
	(generator_version "10.0")
	(general
		(thickness 1.6)
		(legacy_teardrops no)
	)
	(paper "A4")
	(title_block
		(title "04192023_DAF0TMB3IC0_F0TG_MB_C_brd_V02_OCP.brd")
		(comment 1 "Grand Teton / footprints 2993-2994 of 8354")
	)
	(layers
		(0 "F.Cu" signal "TOP")
		(4 "In1.Cu" signal "GND")
		(6 "In2.Cu" signal "IN1")
		(8 "In3.Cu" signal "GND1")
		(10 "In4.Cu" signal "IN2")
		(12 "In5.Cu" signal "GND2")
		(14 "In6.Cu" signal "IN3")
		(16 "In7.Cu" signal "GND3")
		(18 "In8.Cu" signal "VCC")
		(20 "In9.Cu" signal "VCC1")
		(22 "In10.Cu" signal "GND4")
		(24 "In11.Cu" signal "IN4")
		(26 "In12.Cu" signal "GND5")
		(28 "In13.Cu" signal "IN5")
		(30 "In14.Cu" signal "GND6")
		(32 "In15.Cu" signal "IN6")
		(34 "In16.Cu" signal "GND7")
		(2 "B.Cu" signal "BOTTOM")
		(9 "F.Adhes" user "F.Adhesive")
		(11 "B.Adhes" user "B.Adhesive")
		(13 "F.Paste" user "Package Geometry/Pastemask Top")
		(15 "B.Paste" user "Package Geometry/Pastemask Bottom")
		(5 "F.SilkS" user "Ref Des/Silkscreen Top")
		(7 "B.SilkS" user "Ref Des/Silkscreen Bottom")
		(1 "F.Mask" user "Board Geometry/Soldermask Top")
		(3 "B.Mask" user "Board Geometry/Soldermask Bottom")
		(17 "Dwgs.User" user "User.Drawings")
		(19 "Cmts.User" user "User.Comments")
		(21 "Eco1.User" user "User.Eco1")
		(23 "Eco2.User" user "User.Eco2")
		(25 "Edge.Cuts" user "Board Geometry/Outline")
		(27 "Margin" user)
		(31 "F.CrtYd" user "Package Geometry/Place Bound Top")
		(29 "B.CrtYd" user "Package Geometry/Place Bound Bottom")
		(35 "F.Fab" user "Ref Des/Assembly Top")
		(33 "B.Fab" user "Ref Des/Assembly Bottom")
	)
	(footprint ""
		(layer "F.Cu")
		(at 213.19744 -30.246828 90)
		(property "Reference" "R4091"
			(at 0 0 90)
			(layer "F.SilkS")
			(hide yes)
			(effects
				(font
					(size 1.27 1.27)
				)
			)
		)
		(property "Value" ""
			(at 0 0 90)
			(layer "F.Fab")
			(effects
				(font
					(size 1.27 1.27)
				)
			)
		)
		(duplicate_pad_numbers_are_jumpers no)
		(fp_line
			(start 0.7874 -0.4064)
			(end 0.7874 0.4064)
			(stroke
				(width 0.1524)
				(type default)
			)
			(layer "F.SilkS")
		)
		(fp_line
			(start -0.7874 -0.4064)
			(end 0.7874 -0.4064)
			(stroke
				(width 0.1524)
				(type default)
			)
			(layer "F.SilkS")
		)
		(fp_line
			(start 0.7874 0.4064)
			(end -0.7874 0.4064)
			(stroke
				(width 0.1524)
				(type default)
			)
			(layer "F.SilkS")
		)
		(fp_line
			(start -0.7874 0.4064)
			(end -0.7874 -0.4064)
			(stroke
				(width 0.1524)
				(type default)
			)
			(layer "F.SilkS")
		)
		(fp_line
			(start -0.12065 -0.305054)
			(end -0.12065 -0.2794)
			(stroke
				(width 0.1)
				(type default)
			)
			(layer "F.Fab")
		)
		(fp_line
			(start -0.67945 -0.305054)
			(end -0.12065 -0.305054)
			(stroke
				(width 0.1)
				(type default)
			)
			(layer "F.Fab")
		)
		(fp_line
			(start 0.67945 -0.3048)
			(end 0.67945 0.3048)
			(stroke
				(width 0.1)
				(type default)
			)
			(layer "F.Fab")
		)
		(fp_line
			(start 0.12065 -0.3048)
			(end 0.67945 -0.3048)
			(stroke
				(width 0.1)
				(type default)
			)
			(layer "F.Fab")
		)
		(fp_line
			(start 0.12065 -0.2794)
			(end 0.12065 -0.3048)
			(stroke
				(width 0.1)
				(type default)
			)
			(layer "F.Fab")
		)
		(fp_line
			(start -0.12065 -0.2794)
			(end 0.12065 -0.2794)
			(stroke
				(width 0.1)
				(type default)
			)
			(layer "F.Fab")
		)
		(fp_line
			(start 0.120396 0.2794)
			(end -0.12065 0.2794)
			(stroke
				(width 0.1)
				(type default)
			)
			(layer "F.Fab")
		)
		(fp_line
			(start -0.12065 0.2794)
			(end -0.12065 0.3048)
			(stroke
				(width 0.1)
				(type default)
			)
			(layer "F.Fab")
		)
		(fp_line
			(start 0.67945 0.3048)
			(end 0.120396 0.3048)
			(stroke
				(width 0.1)
				(type default)
			)
			(layer "F.Fab")
		)
		(fp_line
			(start 0.120396 0.3048)
			(end 0.120396 0.2794)
			(stroke
				(width 0.1)
				(type default)
			)
			(layer "F.Fab")
		)
		(fp_line
			(start -0.12065 0.3048)
			(end -0.67945 0.3048)
			(stroke
				(width 0.1)
				(type default)
			)
			(layer "F.Fab")
		)
		(fp_line
			(start -0.67945 0.3048)
			(end -0.67945 -0.305054)
			(stroke
				(width 0.1)
				(type default)
			)
			(layer "F.Fab")
		)
		(pad "1" smd circle
			(at -0.40005 0 90)
			(size 0 0)
			(layers "F.Cu" "F.Mask" "F.Paste")
			(net "P3V3_AUX")
		)
		(pad "2" smd circle
			(at 0.40005 0 90)
			(size 0 0)
			(layers "F.Cu" "F.Mask" "F.Paste")
			(net "P12V_SCM_ADC_ALERT_R")
		)
	)
	(footprint ""
		(layer "F.Cu")
		(at 420.031418 -366.202214 90)
		(property "Reference" "PC202_2"
			(at 0 0 90)
			(layer "F.SilkS")
			(hide yes)
			(effects
				(font
					(size 1.27 1.27)
				)
			)
		)
		(property "Value" ""
			(at 0 0 90)
			(layer "F.Fab")
			(effects
				(font
					(size 1.27 1.27)
				)
			)
		)
		(duplicate_pad_numbers_are_jumpers no)
		(fp_line
			(start 0.7874 -0.4064)
			(end 0.7874 0.4064)
			(stroke
				(width 0.1524)
				(type default)
			)
			(layer "F.SilkS")
		)
		(fp_line
			(start -0.7874 -0.4064)
			(end 0.7874 -0.4064)
			(stroke
				(width 0.1524)
				(type default)
			)
			(layer "F.SilkS")
		)
		(fp_line
			(start 0.7874 0.4064)
			(end -0.7874 0.4064)
			(stroke
				(width 0.1524)
				(type default)
			)
			(layer "F.SilkS")
		)
		(fp_line
			(start -0.7874 0.4064)
			(end -0.7874 -0.4064)
			(stroke
				(width 0.1524)
				(type default)
			)
			(layer "F.SilkS")
		)
		(fp_line
			(start -0.12065 -0.305054)
			(end -0.12065 -0.2794)
			(stroke
				(width 0.1)
				(type default)
			)
			(layer "F.Fab")
		)
		(fp_line
			(start -0.67945 -0.305054)
			(end -0.12065 -0.305054)
			(stroke
				(width 0.1)
				(type default)
			)
			(layer "F.Fab")
		)
		(fp_line
			(start 0.67945 -0.3048)
			(end 0.67945 0.3048)
			(stroke
				(width 0.1)
				(type default)
			)
			(layer "F.Fab")
		)
		(fp_line
			(start 0.12065 -0.3048)
			(end 0.67945 -0.3048)
			(stroke
				(width 0.1)
				(type default)
			)
			(layer "F.Fab")
		)
		(fp_line
			(start 0.12065 -0.2794)
			(end 0.12065 -0.3048)
			(stroke
				(width 0.1)
				(type default)
			)
			(layer "F.Fab")
		)
		(fp_line
			(start -0.12065 -0.2794)
			(end 0.12065 -0.2794)
			(stroke
				(width 0.1)
				(type default)
			)
			(layer "F.Fab")
		)
		(fp_line
			(start 0.120396 0.2794)
			(end -0.12065 0.2794)
			(stroke
				(width 0.1)
				(type default)
			)
			(layer "F.Fab")
		)
		(fp_line
			(start -0.12065 0.2794)
			(end -0.12065 0.3048)
			(stroke
				(width 0.1)
				(type default)
			)
			(layer "F.Fab")
		)
		(fp_line
			(start 0.67945 0.3048)
			(end 0.120396 0.3048)
			(stroke
				(width 0.1)
				(type default)
			)
			(layer "F.Fab")
		)
		(fp_line
			(start 0.120396 0.3048)
			(end 0.120396 0.2794)
			(stroke
				(width 0.1)
				(type default)
			)
			(layer "F.Fab")
		)
		(fp_line
			(start -0.12065 0.3048)
			(end -0.67945 0.3048)
			(stroke
				(width 0.1)
				(type default)
			)
			(layer "F.Fab")
		)
		(fp_line
			(start -0.67945 0.3048)
			(end -0.67945 -0.305054)
			(stroke
				(width 0.1)
				(type default)
			)
			(layer "F.Fab")
		)
		(pad "1" smd circle
			(at -0.40005 0 90)
			(size 0 0)
			(layers "F.Cu" "F.Mask" "F.Paste")
			(net "PVDD11_S3_P0_VCCS")
		)
		(pad "2" smd circle
			(at 0.40005 0 90)
			(size 0 0)
			(layers "F.Cu" "F.Mask" "F.Paste")
			(net "GND")
		)
	)
)
